# BASEBOARD_FAB2 (Tioga Pass) — schematic netlist excerpt (pin names and nets, part order shuffled) for the footprints in the layout excerpt that follows; sources: Cadence DE-HDL packaged netlist, KiCad conversion of Wiwynn_Tioga_Pass_MB.brd

C9B7  CAP_A  0.1UF 16V 10% X7R  pkg 0402V  page 167 : A = P3V3_STBY ; B = GND
R6M1  RES  1.00K 1% CHIP  pkg 0402  page 98 : A = PVDDQ_DEF ; B = M_D_VREF
R2P5  RES  4.75K 1% CHIP  pkg 0402  page 170 : A = P3V3_STBY ; B = FM_PMBUS_ALERT_BUF_EN

(kicad_pcb
	(version 20260206)
	(generator "pcbnew")
	(generator_version "10.0")
	(general
		(thickness 1.6)
		(legacy_teardrops no)
	)
	(paper "A4")
	(title_block
		(title "Wiwynn_Tioga_Pass_MB.brd")
		(comment 1 "Tioga Pass / footprints 2379-2381 of 4770")
	)
	(layers
		(0 "F.Cu" signal "TOP")
		(4 "In1.Cu" signal "L2GND")
		(6 "In2.Cu" signal "L3")
		(8 "In3.Cu" signal "L4GND")
		(10 "In4.Cu" signal "L5")
		(12 "In5.Cu" signal "L6GND")
		(14 "In6.Cu" signal "L7VCC")
		(16 "In7.Cu" signal "L8VCC")
		(18 "In8.Cu" signal "L9GND")
		(20 "In9.Cu" signal "L10")
		(22 "In10.Cu" signal "L11GND")
		(24 "In11.Cu" signal "L12")
		(26 "In12.Cu" signal "L13GND")
		(2 "B.Cu" signal "BOTTOM")
		(9 "F.Adhes" user "F.Adhesive")
		(11 "B.Adhes" user "B.Adhesive")
		(13 "F.Paste" user "Package Geometry/Pastemask Top")
		(15 "B.Paste" user "Package Geometry/Pastemask Bottom")
		(5 "F.SilkS" user "Ref Des/Silkscreen Top")
		(7 "B.SilkS" user "Ref Des/Silkscreen Bottom")
		(1 "F.Mask" user "Board Geometry/Soldermask Top")
		(3 "B.Mask" user "Board Geometry/Soldermask Bottom")
		(17 "Dwgs.User" user "User.Drawings")
		(19 "Cmts.User" user "User.Comments")
		(21 "Eco1.User" user "User.Eco1")
		(23 "Eco2.User" user "User.Eco2")
		(25 "Edge.Cuts" user "Board Geometry/Outline")
		(27 "Margin" user)
		(31 "F.CrtYd" user "Package Geometry/Place Bound Top")
		(29 "B.CrtYd" user "Package Geometry/Place Bound Bottom")
		(35 "F.Fab" user "Ref Des/Assembly Top")
		(33 "B.Fab" user "Ref Des/Assembly Bottom")
	)
	(footprint ""
		(layer "B.Cu")
		(at 419.220142 -82.042)
		(property "Reference" "R2P5"
			(at 0 0 0)
			(layer "B.SilkS")
			(hide yes)
			(effects
				(font
					(size 1.27 1.27)
				)
				(justify mirror)
			)
		)
		(property "Value" ""
			(at 0 0 0)
			(layer "B.Fab")
			(effects
				(font
					(size 1.27 1.27)
				)
				(justify mirror)
			)
		)
		(duplicate_pad_numbers_are_jumpers no)
		(fp_poly
			(pts
				(xy 0.2794 -0.1016) (xy -0.2794 -0.1016) (xy -0.2794 0.9906) (xy 0.2794 0.9906)
			)
			(stroke
				(width 0)
				(type default)
			)
			(fill no)
			(layer "B.CrtYd")
		)
		(fp_line
			(start -0.2794 -0.1016)
			(end 0.2794 -0.1016)
			(stroke
				(width 0.1)
				(type default)
			)
			(layer "B.Fab")
		)
		(fp_line
			(start -0.2794 0.9906)
			(end -0.2794 -0.1016)
			(stroke
				(width 0.1)
				(type default)
			)
			(layer "B.Fab")
		)
		(fp_line
			(start 0.2794 -0.1016)
			(end 0.2794 0.9906)
			(stroke
				(width 0.1)
				(type default)
			)
			(layer "B.Fab")
		)
		(fp_line
			(start 0.2794 0.9906)
			(end -0.2794 0.9906)
			(stroke
				(width 0.1)
				(type default)
			)
			(layer "B.Fab")
		)
		(pad "1" smd rect
			(at 0 0 180)
			(size 0.508 0.508)
			(layers "B.Cu" "B.Mask" "B.Paste")
			(net "P3V3_STBY")
		)
		(pad "2" smd rect
			(at 0 0.889 180)
			(size 0.508 0.508)
			(layers "B.Cu" "B.Mask" "B.Paste")
			(net "FM_PMBUS_ALERT_BUF_EN")
		)
		(zone
			(layer "B.Cu")
			(hatch none 0.5)
			(connect_pads
				(clearance 0)
			)
			(min_thickness 0.25)
			(keepout
				(tracks allowed)
				(vias not_allowed)
				(pads allowed)
				(copperpour not_allowed)
				(footprints allowed)
			)
			(placement
				(enabled no)
				(sheetname "")
			)
			(fill
				(thermal_gap 0.5)
				(thermal_bridge_width 0.5)
				(island_removal_mode 0)
			)
			(polygon
				(pts
					(xy 419.474142 -81.788) (xy 418.966142 -81.788) (xy 418.966142 -81.407) (xy 419.474142 -81.407)
				)
			)
		)
		(zone
			(layer "B.Cu")
			(hatch none 0.5)
			(connect_pads
				(clearance 0)
			)
			(min_thickness 0.25)
			(keepout
				(tracks not_allowed)
				(vias allowed)
				(pads allowed)
				(copperpour not_allowed)
				(footprints allowed)
			)
			(placement
				(enabled no)
				(sheetname "")
			)
			(fill
				(thermal_gap 0.5)
				(thermal_bridge_width 0.5)
				(island_removal_mode 0)
			)
			(polygon
				(pts
					(xy 419.474142 -81.407) (xy 418.966142 -81.407) (xy 418.966142 -81.788) (xy 419.474142 -81.788)
				)
			)
		)
	)
	(footprint ""
		(layer "B.Cu")
		(at 193.802 -134.874 180)
		(property "Reference" "R6M1"
			(at 0 0 0)
			(layer "B.SilkS")
			(hide yes)
			(effects
				(font
					(size 1.27 1.27)
				)
				(justify mirror)
			)
		)
		(property "Value" ""
			(at 0 0 0)
			(layer "B.Fab")
			(effects
				(font
					(size 1.27 1.27)
				)
				(justify mirror)
			)
		)
		(duplicate_pad_numbers_are_jumpers no)
		(fp_poly
			(pts
				(xy 0.2794 -0.1016) (xy -0.2794 -0.1016) (xy -0.2794 0.9906) (xy 0.2794 0.9906)
			)
			(stroke
				(width 0)
				(type default)
			)
			(fill no)
			(layer "B.CrtYd")
		)
		(fp_line
			(start 0.2794 0.9906)
			(end -0.2794 0.9906)
			(stroke
				(width 0.1)
				(type default)
			)
			(layer "B.Fab")
		)
		(fp_line
			(start 0.2794 -0.1016)
			(end 0.2794 0.9906)
			(stroke
				(width 0.1)
				(type default)
			)
			(layer "B.Fab")
		)
		(fp_line
			(start -0.2794 0.9906)
			(end -0.2794 -0.1016)
			(stroke
				(width 0.1)
				(type default)
			)
			(layer "B.Fab")
		)
		(fp_line
			(start -0.2794 -0.1016)
			(end 0.2794 -0.1016)
			(stroke
				(width 0.1)
				(type default)
			)
			(layer "B.Fab")
		)
		(pad "1" smd rect
			(at 0 0)
			(size 0.508 0.508)
			(layers "B.Cu" "B.Mask" "B.Paste")
			(net "PVDDQ_DEF")
		)
		(pad "2" smd rect
			(at 0 0.889)
			(size 0.508 0.508)
			(layers "B.Cu" "B.Mask" "B.Paste")
			(net "M_D_VREF")
		)
		(zone
			(layer "B.Cu")
			(hatch none 0.5)
			(connect_pads
				(clearance 0)
			)
			(min_thickness 0.25)
			(keepout
				(tracks not_allowed)
				(vias allowed)
				(pads allowed)
				(copperpour not_allowed)
				(footprints allowed)
			)
			(placement
				(enabled no)
				(sheetname "")
			)
			(fill
				(thermal_gap 0.5)
				(thermal_bridge_width 0.5)
				(island_removal_mode 0)
			)
			(polygon
				(pts
					(xy 193.548 -135.509) (xy 194.056 -135.509) (xy 194.056 -135.128) (xy 193.548 -135.128)
				)
			)
		)
		(zone
			(layer "B.Cu")
			(hatch none 0.5)
			(connect_pads
				(clearance 0)
			)
			(min_thickness 0.25)
			(keepout
				(tracks allowed)
				(vias not_allowed)
				(pads allowed)
				(copperpour not_allowed)
				(footprints allowed)
			)
			(placement
				(enabled no)
				(sheetname "")
			)
			(fill
				(thermal_gap 0.5)
				(thermal_bridge_width 0.5)
				(island_removal_mode 0)
			)
			(polygon
				(pts
					(xy 193.548 -135.128) (xy 194.056 -135.128) (xy 194.056 -135.509) (xy 193.548 -135.509)
				)
			)
		)
	)
	(footprint ""
		(layer "B.Cu")
		(at 493.06734 -123.06808 90)
		(property "Reference" "C9B7"
			(at 0 0 90)
			(layer "B.SilkS")
			(hide yes)
			(effects
				(font
					(size 1.27 1.27)
				)
				(justify mirror)
			)
		)
		(property "Value" ""
			(at 0 0 90)
			(layer "B.Fab")
			(effects
				(font
					(size 1.27 1.27)
				)
				(justify mirror)
			)
		)
		(duplicate_pad_numbers_are_jumpers no)
		(fp_poly
			(pts
				(xy -0.3048 -0.1016) (xy -0.3048 0.9906) (xy 0.3048 0.9906) (xy 0.3048 -0.1016)
			)
			(stroke
				(width 0)
				(type default)
			)
			(fill no)
			(layer "B.CrtYd")
		)
		(fp_line
			(start 0.3048 -0.1016)
			(end 0.3048 0.9906)
			(stroke
				(width 0.1)
				(type default)
			)
			(layer "B.Fab")
		)
		(fp_line
			(start -0.3048 -0.1016)
			(end 0.3048 -0.1016)
			(stroke
				(width 0.1)
				(type default)
			)
			(layer "B.Fab")
		)
		(fp_line
			(start 0.3048 0.9906)
			(end -0.3048 0.9906)
			(stroke
				(width 0.1)
				(type default)
			)
			(layer "B.Fab")
		)
		(fp_line
			(start -0.3048 0.9906)
			(end -0.3048 -0.1016)
			(stroke
				(width 0.1)
				(type default)
			)
			(layer "B.Fab")
		)
		(pad "1" smd rect
			(at 0 0 270)
			(size 0.508 0.508)
			(layers "B.Cu" "B.Mask" "B.Paste")
			(net "P3V3_STBY")
		)
		(pad "2" smd rect
			(at 0 0.889 270)
			(size 0.508 0.508)
			(layers "B.Cu" "B.Mask" "B.Paste")
			(net "GND")
		)
		(zone
			(layer "B.Cu")
			(hatch none 0.5)
			(connect_pads
				(clearance 0)
			)
			(min_thickness 0.25)
			(keepout
				(tracks allowed)
				(vias not_allowed)
				(pads allowed)
				(copperpour not_allowed)
				(footprints allowed)
			)
			(placement
				(enabled no)
				(sheetname "")
			)
			(fill
				(thermal_gap 0.5)
				(thermal_bridge_width 0.5)
				(island_removal_mode 0)
			)
			(polygon
				(pts
					(xy 493.32134 -123.32208) (xy 493.32134 -122.81408) (xy 493.70234 -122.81408) (xy 493.70234 -123.32208)
				)
			)
		)
		(zone
			(layer "B.Cu")
			(hatch none 0.5)
			(connect_pads
				(clearance 0)
			)
			(min_thickness 0.25)
			(keepout
				(tracks not_allowed)
				(vias allowed)
				(pads allowed)
				(copperpour not_allowed)
				(footprints allowed)
			)
			(placement
				(enabled no)
				(sheetname "")
			)
			(fill
				(thermal_gap 0.5)
				(thermal_bridge_width 0.5)
				(island_removal_mode 0)
			)
			(polygon
				(pts
					(xy 493.70234 -123.32208) (xy 493.70234 -122.81408) (xy 493.32134 -122.81408) (xy 493.32134 -123.32208)
				)
			)
		)
	)
)
